(kicad_pcb
	(version 20260206)
	(generator "pcbnew")
	(generator_version "10.0")
	(general
		(thickness 1.6)
		(legacy_teardrops no)
	)
	(paper "A4")
	(title_block
		(title "Bryce Canyon_IOM_IOC_16318-2_OCP.brd")
		(comment 1 "Bryce Canyon / footprints 383-390 of 1605")
	)
	(layers
		(0 "F.Cu" signal "TOP")
		(4 "In1.Cu" signal "L2GND")
		(6 "In2.Cu" signal "L3")
		(8 "In3.Cu" signal "L4VCC")
		(10 "In4.Cu" signal "L5VCC")
		(12 "In5.Cu" signal "L6")
		(14 "In6.Cu" signal "L7GND")
		(2 "B.Cu" signal "BOTTOM")
		(9 "F.Adhes" user "F.Adhesive")
		(11 "B.Adhes" user "B.Adhesive")
		(13 "F.Paste" user "Package Geometry/Pastemask Top")
		(15 "B.Paste" user "Package Geometry/Pastemask Bottom")
		(5 "F.SilkS" user "Ref Des/Silkscreen Top")
		(7 "B.SilkS" user "Ref Des/Silkscreen Bottom")
		(1 "F.Mask" user "Board Geometry/Soldermask Top")
		(3 "B.Mask" user "Board Geometry/Soldermask Bottom")
		(17 "Dwgs.User" user "User.Drawings")
		(19 "Cmts.User" user "User.Comments")
		(21 "Eco1.User" user "User.Eco1")
		(23 "Eco2.User" user "User.Eco2")
		(25 "Edge.Cuts" user "Board Geometry/Outline")
		(27 "Margin" user)
		(31 "F.CrtYd" user "Package Geometry/Place Bound Top")
		(29 "B.CrtYd" user "Package Geometry/Place Bound Bottom")
		(35 "F.Fab" user "Ref Des/Assembly Top")
		(33 "B.Fab" user "Ref Des/Assembly Bottom")
	)
	(footprint ""
		(layer "F.Cu")
		(at 175.768 -135.4582 180)
		(property "Reference" "L6"
			(at 0 0 180)
			(layer "F.SilkS")
			(hide yes)
			(effects
				(font
					(size 1.27 1.27)
				)
			)
		)
		(property "Value" "BLM21PG220SN1DGP"
			(at 0.0254 -5.6896 180)
			(unlocked yes)
			(layer "F.Fab")
			(hide yes)
			(effects
				(font
					(size 1.016 1.016)
					(thickness 0.1524)
				)
			)
		)
		(property "Device Type" "L20125H42"
			(at 0.0254 -7.5946 180)
			(unlocked yes)
			(layer "F.Fab")
			(hide yes)
			(effects
				(font
					(size 1.016 1.016)
					(thickness 0.1524)
				)
			)
		)
		(duplicate_pad_numbers_are_jumpers no)
		(fp_line
			(start 0.9144 1.7018)
			(end 0.9144 -1.7018)
			(stroke
				(width 0.1524)
				(type default)
			)
			(layer "F.SilkS")
		)
		(fp_line
			(start 0.9144 -1.7018)
			(end -0.9144 -1.7018)
			(stroke
				(width 0.1524)
				(type default)
			)
			(layer "F.SilkS")
		)
		(fp_line
			(start -0.9144 1.7018)
			(end 0.9144 1.7018)
			(stroke
				(width 0.1524)
				(type default)
			)
			(layer "F.SilkS")
		)
		(fp_line
			(start -0.9144 -1.7018)
			(end -0.9144 1.7018)
			(stroke
				(width 0.1524)
				(type default)
			)
			(layer "F.SilkS")
		)
		(fp_rect
			(start -1.0033 1.778)
			(end 1.0033 -1.778)
			(stroke
				(width 0)
				(type default)
			)
			(fill no)
			(layer "F.CrtYd")
		)
		(fp_poly
			(pts
				(xy -1.0033 -1.778) (xy 1.0033 -1.778) (xy 1.0033 1.778) (xy -1.0033 1.778)
			)
			(stroke
				(width 0)
				(type default)
			)
			(fill no)
			(layer "F.Fab")
		)
		(pad "1" smd rect
			(at 0 -0.9652 180)
			(size 1.397 1.143)
			(layers "F.Cu" "F.Mask" "F.Paste")
			(net "P12V_STBY")
		)
		(pad "2" smd rect
			(at 0 0.9652 180)
			(size 1.397 1.143)
			(layers "F.Cu" "F.Mask" "F.Paste")
			(net "P12V_STBY_VIN_PU1")
		)
	)
	(footprint ""
		(layer "F.Cu")
		(at 169.1894 -165.9128 -90)
		(property "Reference" "C167"
			(at 0 0 270)
			(layer "F.SilkS")
			(hide yes)
			(effects
				(font
					(size 1.27 1.27)
				)
			)
		)
		(property "Value" "ST100U16VDM-3-GP"
			(at 0 -9.6012 270)
			(unlocked yes)
			(layer "F.Fab")
			(hide yes)
			(effects
				(font
					(size 1.016 1.016)
					(thickness 0.1524)
				)
			)
		)
		(property "Device Type" "CT7343H79"
			(at 0 -11.1252 270)
			(unlocked yes)
			(layer "F.Fab")
			(hide yes)
			(effects
				(font
					(size 1.016 1.016)
					(thickness 0.1524)
				)
			)
		)
		(duplicate_pad_numbers_are_jumpers no)
		(fp_line
			(start -2.286 4.8768)
			(end -2.286 2.032)
			(stroke
				(width 0.1524)
				(type default)
			)
			(layer "F.SilkS")
		)
		(fp_line
			(start 2.286 4.8768)
			(end -2.286 4.8768)
			(stroke
				(width 0.1524)
				(type default)
			)
			(layer "F.SilkS")
		)
		(fp_line
			(start 2.286 2.032)
			(end 2.286 4.8768)
			(stroke
				(width 0.1524)
				(type default)
			)
			(layer "F.SilkS")
		)
		(fp_line
			(start 2.286 -2.032)
			(end 2.286 -4.8768)
			(stroke
				(width 0.1524)
				(type default)
			)
			(layer "F.SilkS")
		)
		(fp_line
			(start 2.1082 -4.699)
			(end -2.1082 -4.699)
			(stroke
				(width 0.508)
				(type default)
			)
			(layer "F.SilkS")
		)
		(fp_line
			(start -2.286 -4.8768)
			(end -2.286 -2.032)
			(stroke
				(width 0.1524)
				(type default)
			)
			(layer "F.SilkS")
		)
		(fp_line
			(start 2.286 -4.8768)
			(end -2.286 -4.8768)
			(stroke
				(width 0.1524)
				(type default)
			)
			(layer "F.SilkS")
		)
		(fp_rect
			(start -2.1463 3.6449)
			(end 2.1463 -3.6449)
			(stroke
				(width 0)
				(type default)
			)
			(fill no)
			(layer "F.CrtYd")
		)
		(fp_poly
			(pts
				(xy -2.54 4.953) (xy -2.54 4.2926) (xy -3.81 4.2926) (xy -3.81 -4.2926) (xy -2.54 -4.2926) (xy -2.54 -4.953)
				(xy 2.54 -4.953) (xy 2.54 -4.2926) (xy 3.81 -4.2926) (xy 3.81 -1.6256) (xy 2.1463 -1.6256) (xy 2.1463 -3.6449)
				(xy -2.1463 -3.6449) (xy -2.1463 3.6449) (xy 2.1463 3.6449) (xy 2.1463 -1.6129) (xy 3.81 -1.6129)
				(xy 3.81 4.2926) (xy 2.54 4.2926) (xy 2.54 4.953)
			)
			(stroke
				(width 0)
				(type default)
			)
			(fill no)
			(layer "F.CrtYd")
		)
		(fp_rect
			(start -2.54 4.953)
			(end 2.54 -4.953)
			(stroke
				(width 0)
				(type default)
			)
			(fill no)
			(layer "F.Fab")
		)
		(fp_rect
			(start -3.81 4.2926)
			(end -2.54 -4.2926)
			(stroke
				(width 0)
				(type default)
			)
			(fill no)
			(layer "F.Fab")
		)
		(fp_rect
			(start 2.54 4.2926)
			(end 3.81 -4.2926)
			(stroke
				(width 0)
				(type default)
			)
			(fill no)
			(layer "F.Fab")
		)
		(pad "1" smd rect
			(at 0 -3.1496 270)
			(size 2.413 2.286)
			(layers "F.Cu" "F.Mask" "F.Paste")
			(net "P5V_STBY")
		)
		(pad "2" smd rect
			(at 0 3.1496 270)
			(size 2.413 2.286)
			(layers "F.Cu" "F.Mask" "F.Paste")
			(net "GND")
		)
		(zone
			(layer "F.Cu")
			(hatch none 0.5)
			(connect_pads
				(clearance 0)
			)
			(min_thickness 0.25)
			(keepout
				(tracks allowed)
				(vias not_allowed)
				(pads allowed)
				(copperpour not_allowed)
				(footprints allowed)
			)
			(placement
				(enabled no)
				(sheetname "")
			)
			(fill
				(thermal_gap 0.5)
				(thermal_bridge_width 0.5)
				(island_removal_mode 0)
			)
			(polygon
				(pts
					(xy 164.592 -167.4241) (xy 164.592 -164.4015) (xy 167.4876 -164.4015) (xy 167.8178 -164.4015) (xy 167.8178 -167.4241)
					(xy 167.4876 -167.4241)
				)
			)
		)
		(zone
			(layer "F.Cu")
			(hatch none 0.5)
			(connect_pads
				(clearance 0)
			)
			(min_thickness 0.25)
			(keepout
				(tracks allowed)
				(vias not_allowed)
				(pads allowed)
				(copperpour not_allowed)
				(footprints allowed)
			)
			(placement
				(enabled no)
				(sheetname "")
			)
			(fill
				(thermal_gap 0.5)
				(thermal_bridge_width 0.5)
				(island_removal_mode 0)
			)
			(polygon
				(pts
					(xy 170.8785 -164.4015) (xy 173.7868 -164.4015) (xy 173.7868 -167.4241) (xy 170.8912 -167.4241)
					(xy 170.561 -167.4241) (xy 170.561 -164.4015)
				)
			)
		)
	)
	(footprint ""
		(layer "F.Cu")
		(at 177.34788 -50.22596 90)
		(property "Reference" "R662"
			(at 0 0 90)
			(layer "F.SilkS")
			(hide yes)
			(effects
				(font
					(size 1.27 1.27)
				)
			)
		)
		(property "Value" "10KR2F-2-GP"
			(at 0.064008 -3.993896 90)
			(unlocked yes)
			(layer "F.Fab")
			(hide yes)
			(effects
				(font
					(size 1.016 1.016)
					(thickness 0.1524)
				)
			)
		)
		(property "Device Type" "R402H16"
			(at 0.064008 -5.517896 90)
			(unlocked yes)
			(layer "F.Fab")
			(hide yes)
			(effects
				(font
					(size 1.016 1.016)
					(thickness 0.1524)
				)
			)
		)
		(duplicate_pad_numbers_are_jumpers no)
		(fp_line
			(start 0.508 -0.9398)
			(end -0.508 -0.9398)
			(stroke
				(width 0.1524)
				(type default)
			)
			(layer "F.SilkS")
		)
		(fp_line
			(start -0.508 -0.9398)
			(end -0.508 0.9398)
			(stroke
				(width 0.1524)
				(type default)
			)
			(layer "F.SilkS")
		)
		(fp_rect
			(start -0.508 0.9398)
			(end 0.508 -0.9398)
			(stroke
				(width 0)
				(type default)
			)
			(fill no)
			(layer "F.CrtYd")
		)
		(fp_rect
			(start -0.508 0.9398)
			(end 0.508 -0.9398)
			(stroke
				(width 0)
				(type default)
			)
			(fill no)
			(layer "F.Fab")
		)
		(pad "1" smd custom
			(at 0 -0.4445 90)
			(size 0.1397 0.1397)
			(layers "F.Cu" "F.Mask" "F.Paste")
			(net "P1V8")
			(options
				(clearance outline)
				(anchor circle)
			)
			(primitives
				(gr_poly
					(pts
						(arc
							(start -0.1778 -0.2794)
							(mid -0.249642 -0.249642)
							(end -0.2794 -0.1778)
						)
						(arc
							(start -0.2794 0.1778)
							(mid -0.249642 0.249642)
							(end -0.1778 0.2794)
						)
						(arc
							(start 0.1778 0.2794)
							(mid 0.249642 0.249642)
							(end 0.2794 0.1778)
						)
						(arc
							(start 0.2794 -0.1778)
							(mid 0.249642 -0.249642)
							(end 0.1778 -0.2794)
						)
					)
					(width 0)
					(fill yes)
				)
			)
		)
		(pad "2" smd custom
			(at 0 0.4445 90)
			(size 0.1397 0.1397)
			(layers "F.Cu" "F.Mask" "F.Paste")
			(net "XM_ADDR_7")
			(options
				(clearance outline)
				(anchor circle)
			)
			(primitives
				(gr_poly
					(pts
						(arc
							(start -0.1778 -0.2794)
							(mid -0.249642 -0.249642)
							(end -0.2794 -0.1778)
						)
						(arc
							(start -0.2794 0.1778)
							(mid -0.249642 0.249642)
							(end -0.1778 0.2794)
						)
						(arc
							(start 0.1778 0.2794)
							(mid 0.249642 0.249642)
							(end 0.2794 0.1778)
						)
						(arc
							(start 0.2794 -0.1778)
							(mid 0.249642 -0.249642)
							(end 0.1778 -0.2794)
						)
					)
					(width 0)
					(fill yes)
				)
			)
		)
	)
	(footprint ""
		(layer "F.Cu")
		(at 158.302706 -86.151466 180)
		(property "Reference" "R693"
			(at 0 0 180)
			(layer "F.SilkS")
			(hide yes)
			(effects
				(font
					(size 1.27 1.27)
				)
			)
		)
		(property "Value" "0R2J-2-GP"
			(at 0.064008 -3.993896 180)
			(unlocked yes)
			(layer "F.Fab")
			(hide yes)
			(effects
				(font
					(size 1.016 1.016)
					(thickness 0.1524)
				)
			)
		)
		(property "Device Type" "R402H16"
			(at 0.064008 -5.517896 180)
			(unlocked yes)
			(layer "F.Fab")
			(hide yes)
			(effects
				(font
					(size 1.016 1.016)
					(thickness 0.1524)
				)
			)
		)
		(duplicate_pad_numbers_are_jumpers no)
		(fp_line
			(start 0.508 -0.9398)
			(end -0.508 -0.9398)
			(stroke
				(width 0.1524)
				(type default)
			)
			(layer "F.SilkS")
		)
		(fp_line
			(start -0.508 -0.9398)
			(end -0.508 0.9398)
			(stroke
				(width 0.1524)
				(type default)
			)
			(layer "F.SilkS")
		)
		(fp_rect
			(start -0.508 0.9398)
			(end 0.508 -0.9398)
			(stroke
				(width 0)
				(type default)
			)
			(fill no)
			(layer "F.CrtYd")
		)
		(fp_rect
			(start -0.508 0.9398)
			(end 0.508 -0.9398)
			(stroke
				(width 0)
				(type default)
			)
			(fill no)
			(layer "F.Fab")
		)
		(pad "1" smd custom
			(at 0 -0.4445 180)
			(size 0.1397 0.1397)
			(layers "F.Cu" "F.Mask" "F.Paste")
			(net "IOC_UART_0_RX_R")
			(options
				(clearance outline)
				(anchor circle)
			)
			(primitives
				(gr_poly
					(pts
						(arc
							(start -0.1778 -0.2794)
							(mid -0.249642 -0.249642)
							(end -0.2794 -0.1778)
						)
						(arc
							(start -0.2794 0.1778)
							(mid -0.249642 0.249642)
							(end -0.1778 0.2794)
						)
						(arc
							(start 0.1778 0.2794)
							(mid 0.249642 0.249642)
							(end 0.2794 0.1778)
						)
						(arc
							(start 0.2794 -0.1778)
							(mid 0.249642 -0.249642)
							(end 0.1778 -0.2794)
						)
					)
					(width 0)
					(fill yes)
				)
			)
		)
		(pad "2" smd custom
			(at 0 0.4445 180)
			(size 0.1397 0.1397)
			(layers "F.Cu" "F.Mask" "F.Paste")
			(net "IOC_UART_0_RX")
			(options
				(clearance outline)
				(anchor circle)
			)
			(primitives
				(gr_poly
					(pts
						(arc
							(start -0.1778 -0.2794)
							(mid -0.249642 -0.249642)
							(end -0.2794 -0.1778)
						)
						(arc
							(start -0.2794 0.1778)
							(mid -0.249642 0.249642)
							(end -0.1778 0.2794)
						)
						(arc
							(start 0.1778 0.2794)
							(mid 0.249642 0.249642)
							(end 0.2794 0.1778)
						)
						(arc
							(start 0.2794 -0.1778)
							(mid 0.249642 -0.249642)
							(end 0.1778 -0.2794)
						)
					)
					(width 0)
					(fill yes)
				)
			)
		)
	)
	(footprint ""
		(layer "F.Cu")
		(at 173.568868 -62.114938 -90)
		(property "Reference" "R572"
			(at 0 0 270)
			(layer "F.SilkS")
			(hide yes)
			(effects
				(font
					(size 1.27 1.27)
				)
			)
		)
		(property "Value" "10KR2F-2-GP"
			(at 0.064008 -3.993896 270)
			(unlocked yes)
			(layer "F.Fab")
			(hide yes)
			(effects
				(font
					(size 1.016 1.016)
					(thickness 0.1524)
				)
			)
		)
		(property "Device Type" "R402H16"
			(at 0.064008 -5.517896 270)
			(unlocked yes)
			(layer "F.Fab")
			(hide yes)
			(effects
				(font
					(size 1.016 1.016)
					(thickness 0.1524)
				)
			)
		)
		(duplicate_pad_numbers_are_jumpers no)
		(fp_line
			(start -0.508 -0.9398)
			(end -0.508 0.9398)
			(stroke
				(width 0.1524)
				(type default)
			)
			(layer "F.SilkS")
		)
		(fp_line
			(start 0.508 -0.9398)
			(end -0.508 -0.9398)
			(stroke
				(width 0.1524)
				(type default)
			)
			(layer "F.SilkS")
		)
		(fp_rect
			(start -0.508 0.9398)
			(end 0.508 -0.9398)
			(stroke
				(width 0)
				(type default)
			)
			(fill no)
			(layer "F.CrtYd")
		)
		(fp_rect
			(start -0.508 0.9398)
			(end 0.508 -0.9398)
			(stroke
				(width 0)
				(type default)
			)
			(fill no)
			(layer "F.Fab")
		)
		(pad "1" smd custom
			(at 0 -0.4445 270)
			(size 0.1397 0.1397)
			(layers "F.Cu" "F.Mask" "F.Paste")
			(net "IOC_CLK_SEL0")
			(options
				(clearance outline)
				(anchor circle)
			)
			(primitives
				(gr_poly
					(pts
						(arc
							(start -0.1778 -0.2794)
							(mid -0.249642 -0.249642)
							(end -0.2794 -0.1778)
						)
						(arc
							(start -0.2794 0.1778)
							(mid -0.249642 0.249642)
							(end -0.1778 0.2794)
						)
						(arc
							(start 0.1778 0.2794)
							(mid 0.249642 0.249642)
							(end 0.2794 0.1778)
						)
						(arc
							(start 0.2794 -0.1778)
							(mid 0.249642 -0.249642)
							(end 0.1778 -0.2794)
						)
					)
					(width 0)
					(fill yes)
				)
			)
		)
		(pad "2" smd custom
			(at 0 0.4445 270)
			(size 0.1397 0.1397)
			(layers "F.Cu" "F.Mask" "F.Paste")
			(net "P1V8")
			(options
				(clearance outline)
				(anchor circle)
			)
			(primitives
				(gr_poly
					(pts
						(arc
							(start -0.1778 -0.2794)
							(mid -0.249642 -0.249642)
							(end -0.2794 -0.1778)
						)
						(arc
							(start -0.2794 0.1778)
							(mid -0.249642 0.249642)
							(end -0.1778 0.2794)
						)
						(arc
							(start 0.1778 0.2794)
							(mid 0.249642 0.249642)
							(end 0.2794 0.1778)
						)
						(arc
							(start 0.2794 -0.1778)
							(mid 0.249642 -0.249642)
							(end 0.1778 -0.2794)
						)
					)
					(width 0)
					(fill yes)
				)
			)
		)
	)
	(footprint ""
		(layer "F.Cu")
		(at 179.167536 -118.79072)
		(property "Reference" "U95"
			(at 0 0 0)
			(layer "F.SilkS")
			(hide yes)
			(effects
				(font
					(size 1.27 1.27)
				)
			)
		)
		(property "Value" "SN74LVC1G07DCKR-GP"
			(at -2.3368 -8.6868 0)
			(unlocked yes)
			(layer "F.Fab")
			(hide yes)
			(effects
				(font
					(size 1.016 1.016)
					(thickness 0.1524)
				)
			)
		)
		(property "Device Type" "SC70-5H44"
			(at -2.3114 -10.414 0)
			(unlocked yes)
			(layer "F.Fab")
			(hide yes)
			(effects
				(font
					(size 1.016 1.016)
					(thickness 0.1524)
				)
			)
		)
		(duplicate_pad_numbers_are_jumpers no)
		(fp_line
			(start -1.27 -1.7018)
			(end 1.27 -1.7018)
			(stroke
				(width 0.1524)
				(type default)
			)
			(layer "F.SilkS")
		)
		(fp_line
			(start -1.27 1.7018)
			(end -1.27 -1.7018)
			(stroke
				(width 0.1524)
				(type default)
			)
			(layer "F.SilkS")
		)
		(fp_line
			(start 0.6604 -1.8034)
			(end 1.3843 -1.8034)
			(stroke
				(width 0.3302)
				(type default)
			)
			(layer "F.SilkS")
		)
		(fp_line
			(start 1.27 -1.7018)
			(end 1.27 1.7018)
			(stroke
				(width 0.1524)
				(type default)
			)
			(layer "F.SilkS")
		)
		(fp_line
			(start 1.27 1.7018)
			(end -1.27 1.7018)
			(stroke
				(width 0.1524)
				(type default)
			)
			(layer "F.SilkS")
		)
		(fp_line
			(start 1.3843 -1.8034)
			(end 1.3843 -1.1176)
			(stroke
				(width 0.3302)
				(type default)
			)
			(layer "F.SilkS")
		)
		(fp_rect
			(start -1.524 1.9558)
			(end 1.524 -1.9558)
			(stroke
				(width 0)
				(type default)
			)
			(fill no)
			(layer "F.CrtYd")
		)
		(fp_poly
			(pts
				(xy -1.524 -1.9558) (xy 1.524 -1.9558) (xy 1.524 1.9558) (xy -1.524 1.9558)
			)
			(stroke
				(width 0)
				(type default)
			)
			(fill no)
			(layer "F.Fab")
		)
		(pad "1" smd rect
			(at 0.65024 -0.8255)
			(size 0.4064 1.2192)
			(layers "F.Cu" "F.Mask" "F.Paste")
			(net "Net_311")
		)
		(pad "2" smd rect
			(at 0 -0.8255)
			(size 0.4064 1.2192)
			(layers "F.Cu" "F.Mask" "F.Paste")
			(net "IOM_FULL_PGOOD")
		)
		(pad "3" smd rect
			(at -0.65024 -0.8255)
			(size 0.4064 1.2192)
			(layers "F.Cu" "F.Mask" "F.Paste")
			(net "GND")
		)
		(pad "4" smd rect
			(at -0.65024 0.8255)
			(size 0.4064 1.2192)
			(layers "F.Cu" "F.Mask" "F.Paste")
			(net "PWRGD_P0V975")
		)
		(pad "5" smd rect
			(at 0.65024 0.8255)
			(size 0.4064 1.2192)
			(layers "F.Cu" "F.Mask" "F.Paste")
			(net "P3V3_STBY")
		)
	)
	(footprint ""
		(layer "F.Cu")
		(at 60.5028 -133.2484)
		(property "Reference" "TP193"
			(at 0 0 0)
			(layer "F.SilkS")
			(hide yes)
			(effects
				(font
					(size 1.27 1.27)
				)
			)
		)
		(property "Value" "TPAD28-2-GP"
			(at -0.0127 -1.6637 0)
			(unlocked yes)
			(layer "F.Fab")
			(hide yes)
			(effects
				(font
					(size 1.016 1.016)
					(thickness 0.1524)
				)
			)
		)
		(property "Device Type" "TPAD28"
			(at -0.0127 -3.1877 0)
			(unlocked yes)
			(layer "F.Fab")
			(hide yes)
			(effects
				(font
					(size 1.016 1.016)
					(thickness 0.1524)
				)
			)
		)
		(duplicate_pad_numbers_are_jumpers no)
		(fp_poly
			(pts
				(arc
					(start 0.3556 0)
					(mid -0.3556 0)
					(end 0.3556 0)
				)
			)
			(stroke
				(width 0)
				(type default)
			)
			(fill no)
			(layer "F.CrtYd")
		)
		(fp_poly
			(pts
				(arc
					(start 0.6096 0)
					(mid -0.6096 0)
					(end 0.6096 0)
				)
			)
			(stroke
				(width 0)
				(type default)
			)
			(fill no)
			(layer "F.Fab")
		)
		(pad "1" smd circle
			(at 0 0)
			(size 0.7112 0.7112)
			(layers "F.Cu" "F.Mask" "F.Paste")
			(net "TP_BMC_EXT2_LED_B")
		)
	)
	(footprint ""
		(layer "F.Cu")
		(at 23.0886 -171.2976 90)
		(property "Reference" "C232"
			(at 0 0 90)
			(layer "F.SilkS")
			(hide yes)
			(effects
				(font
					(size 1.27 1.27)
				)
			)
		)
		(property "Value" "SC10U6D3V5KX-4GP"
			(at -0.0762 -6.1214 90)
			(unlocked yes)
			(layer "F.Fab")
			(hide yes)
			(effects
				(font
					(size 1.016 1.016)
					(thickness 0.1524)
				)
			)
		)
		(property "Device Type" "C805H58"
			(at -0.0762 -8.1534 90)
			(unlocked yes)
			(layer "F.Fab")
			(hide yes)
			(effects
				(font
					(size 1.016 1.016)
					(thickness 0.1524)
				)
			)
		)
		(duplicate_pad_numbers_are_jumpers no)
		(fp_line
			(start 0.635 0)
			(end -0.635 0)
			(stroke
				(width 0.508)
				(type default)
			)
			(layer "F.SilkS")
		)
		(fp_rect
			(start -0.9652 1.778)
			(end 0.9652 -1.778)
			(stroke
				(width 0)
				(type default)
			)
			(fill no)
			(layer "F.CrtYd")
		)
		(fp_poly
			(pts
				(xy -0.9652 -1.778) (xy 0.9652 -1.778) (xy 0.9652 1.778) (xy -0.9652 1.778)
			)
			(stroke
				(width 0)
				(type default)
			)
			(fill no)
			(layer "F.Fab")
		)
		(pad "1" smd rect
			(at 0 -0.9652 90)
			(size 1.397 1.143)
			(layers "F.Cu" "F.Mask" "F.Paste")
			(net "P1V8_STBY")
		)
		(pad "2" smd rect
			(at 0 0.9652 90)
			(size 1.397 1.143)
			(layers "F.Cu" "F.Mask" "F.Paste")
			(net "GND")
		)
	)
)
